# BASEBOARD_FAB2 (Tioga Pass) — schematic netlist excerpt (pin names and nets, part order shuffled) for the footprints in the layout excerpt that follows; sources: Cadence DE-HDL packaged netlist, KiCad conversion of Wiwynn_Tioga_Pass_MB.brd

CT72  CAP  1000PF 50V 10% X7R  pkg 0402LF  page 212 : A = VR_PVCCIO_CPU0_PH1_SW ; B = VR_PVCCIO_CPU0_PH1_SW_RC
C7G33  CAP  1.0UF 16V 10% X6S  pkg 0402  page 216 : A = VR_PVDDQ_ABC_PH1_VCIN ; B = GND
R7C24  RES  4.02K 1% CHIP  pkg 0402  page 194 : A = VR_PVCCMCP_CPU0_XADDR2 ; B = GND

(kicad_pcb
	(version 20260206)
	(generator "pcbnew")
	(generator_version "10.0")
	(general
		(thickness 1.6)
		(legacy_teardrops no)
	)
	(paper "A4")
	(title_block
		(title "Wiwynn_Tioga_Pass_MB.brd")
		(comment 1 "Tioga Pass / footprints 1759-1761 of 4770")
	)
	(layers
		(0 "F.Cu" signal "TOP")
		(4 "In1.Cu" signal "L2GND")
		(6 "In2.Cu" signal "L3")
		(8 "In3.Cu" signal "L4GND")
		(10 "In4.Cu" signal "L5")
		(12 "In5.Cu" signal "L6GND")
		(14 "In6.Cu" signal "L7VCC")
		(16 "In7.Cu" signal "L8VCC")
		(18 "In8.Cu" signal "L9GND")
		(20 "In9.Cu" signal "L10")
		(22 "In10.Cu" signal "L11GND")
		(24 "In11.Cu" signal "L12")
		(26 "In12.Cu" signal "L13GND")
		(2 "B.Cu" signal "BOTTOM")
		(9 "F.Adhes" user "F.Adhesive")
		(11 "B.Adhes" user "B.Adhesive")
		(13 "F.Paste" user "Package Geometry/Pastemask Top")
		(15 "B.Paste" user "Package Geometry/Pastemask Bottom")
		(5 "F.SilkS" user "Ref Des/Silkscreen Top")
		(7 "B.SilkS" user "Ref Des/Silkscreen Bottom")
		(1 "F.Mask" user "Board Geometry/Soldermask Top")
		(3 "B.Mask" user "Board Geometry/Soldermask Bottom")
		(17 "Dwgs.User" user "User.Drawings")
		(19 "Cmts.User" user "User.Comments")
		(21 "Eco1.User" user "User.Eco1")
		(23 "Eco2.User" user "User.Eco2")
		(25 "Edge.Cuts" user "Board Geometry/Outline")
		(27 "Margin" user)
		(31 "F.CrtYd" user "Package Geometry/Place Bound Top")
		(29 "B.CrtYd" user "Package Geometry/Place Bound Bottom")
		(35 "F.Fab" user "Ref Des/Assembly Top")
		(33 "B.Fab" user "Ref Des/Assembly Bottom")
	)
	(footprint ""
		(layer "F.Cu")
		(at 340.995 -106.426 90)
		(property "Reference" "R7C24"
			(at 0 0 90)
			(layer "F.SilkS")
			(hide yes)
			(effects
				(font
					(size 1.27 1.27)
				)
			)
		)
		(property "Value" ""
			(at 0 0 90)
			(layer "F.Fab")
			(effects
				(font
					(size 1.27 1.27)
				)
			)
		)
		(duplicate_pad_numbers_are_jumpers no)
		(fp_poly
			(pts
				(xy -0.2794 -0.1016) (xy 0.2794 -0.1016) (xy 0.2794 0.9906) (xy -0.2794 0.9906)
			)
			(stroke
				(width 0)
				(type default)
			)
			(fill no)
			(layer "F.CrtYd")
		)
		(fp_line
			(start 0.2794 -0.1016)
			(end -0.2794 -0.1016)
			(stroke
				(width 0.1)
				(type default)
			)
			(layer "F.Fab")
		)
		(fp_line
			(start -0.2794 -0.1016)
			(end -0.2794 0.9906)
			(stroke
				(width 0.1)
				(type default)
			)
			(layer "F.Fab")
		)
		(fp_line
			(start 0.2794 0.9906)
			(end 0.2794 -0.1016)
			(stroke
				(width 0.1)
				(type default)
			)
			(layer "F.Fab")
		)
		(fp_line
			(start -0.2794 0.9906)
			(end 0.2794 0.9906)
			(stroke
				(width 0.1)
				(type default)
			)
			(layer "F.Fab")
		)
		(pad "1" smd rect
			(at 0 0 90)
			(size 0.508 0.508)
			(layers "F.Cu" "F.Mask" "F.Paste")
			(net "VR_PVCCMCP_CPU0_XADDR2")
		)
		(pad "2" smd rect
			(at 0 0.889 90)
			(size 0.508 0.508)
			(layers "F.Cu" "F.Mask" "F.Paste")
			(net "GND")
		)
		(zone
			(layer "F.Cu")
			(hatch none 0.5)
			(connect_pads
				(clearance 0)
			)
			(min_thickness 0.25)
			(keepout
				(tracks allowed)
				(vias not_allowed)
				(pads allowed)
				(copperpour not_allowed)
				(footprints allowed)
			)
			(placement
				(enabled no)
				(sheetname "")
			)
			(fill
				(thermal_gap 0.5)
				(thermal_bridge_width 0.5)
				(island_removal_mode 0)
			)
			(polygon
				(pts
					(xy 341.249 -106.172) (xy 341.249 -106.68) (xy 341.63 -106.68) (xy 341.63 -106.172)
				)
			)
		)
		(zone
			(layer "F.Cu")
			(hatch none 0.5)
			(connect_pads
				(clearance 0)
			)
			(min_thickness 0.25)
			(keepout
				(tracks not_allowed)
				(vias allowed)
				(pads allowed)
				(copperpour not_allowed)
				(footprints allowed)
			)
			(placement
				(enabled no)
				(sheetname "")
			)
			(fill
				(thermal_gap 0.5)
				(thermal_bridge_width 0.5)
				(island_removal_mode 0)
			)
			(polygon
				(pts
					(xy 341.63 -106.172) (xy 341.63 -106.68) (xy 341.249 -106.68) (xy 341.249 -106.172)
				)
			)
		)
	)
	(footprint ""
		(layer "F.Cu")
		(at 348.2086 -10.2108 90)
		(property "Reference" "C7G33"
			(at 0 0 90)
			(layer "F.SilkS")
			(hide yes)
			(effects
				(font
					(size 1.27 1.27)
				)
			)
		)
		(property "Value" ""
			(at 0 0 90)
			(layer "F.Fab")
			(effects
				(font
					(size 1.27 1.27)
				)
			)
		)
		(duplicate_pad_numbers_are_jumpers no)
		(fp_poly
			(pts
				(xy 0.3048 -0.1016) (xy 0.3048 0.9906) (xy -0.3048 0.9906) (xy -0.3048 -0.1016)
			)
			(stroke
				(width 0)
				(type default)
			)
			(fill no)
			(layer "F.CrtYd")
		)
		(fp_line
			(start 0.3048 -0.1016)
			(end -0.3048 -0.1016)
			(stroke
				(width 0.1)
				(type default)
			)
			(layer "F.Fab")
		)
		(fp_line
			(start -0.3048 -0.1016)
			(end -0.3048 0.9906)
			(stroke
				(width 0.1)
				(type default)
			)
			(layer "F.Fab")
		)
		(fp_line
			(start 0.3048 0.9906)
			(end 0.3048 -0.1016)
			(stroke
				(width 0.1)
				(type default)
			)
			(layer "F.Fab")
		)
		(fp_line
			(start -0.3048 0.9906)
			(end 0.3048 0.9906)
			(stroke
				(width 0.1)
				(type default)
			)
			(layer "F.Fab")
		)
		(pad "1" smd rect
			(at 0 0 90)
			(size 0.508 0.508)
			(layers "F.Cu" "F.Mask" "F.Paste")
			(net "VR_PVDDQ_ABC_PH1_VCIN")
		)
		(pad "2" smd rect
			(at 0 0.889 90)
			(size 0.508 0.508)
			(layers "F.Cu" "F.Mask" "F.Paste")
			(net "GND")
		)
		(zone
			(layer "F.Cu")
			(hatch none 0.5)
			(connect_pads
				(clearance 0)
			)
			(min_thickness 0.25)
			(keepout
				(tracks allowed)
				(vias not_allowed)
				(pads allowed)
				(copperpour not_allowed)
				(footprints allowed)
			)
			(placement
				(enabled no)
				(sheetname "")
			)
			(fill
				(thermal_gap 0.5)
				(thermal_bridge_width 0.5)
				(island_removal_mode 0)
			)
			(polygon
				(pts
					(xy 348.4626 -9.9568) (xy 348.4626 -10.4648) (xy 348.8436 -10.4648) (xy 348.8436 -9.9568)
				)
			)
		)
		(zone
			(layer "F.Cu")
			(hatch none 0.5)
			(connect_pads
				(clearance 0)
			)
			(min_thickness 0.25)
			(keepout
				(tracks not_allowed)
				(vias allowed)
				(pads allowed)
				(copperpour not_allowed)
				(footprints allowed)
			)
			(placement
				(enabled no)
				(sheetname "")
			)
			(fill
				(thermal_gap 0.5)
				(thermal_bridge_width 0.5)
				(island_removal_mode 0)
			)
			(polygon
				(pts
					(xy 348.8436 -9.9568) (xy 348.8436 -10.4648) (xy 348.4626 -10.4648) (xy 348.4626 -9.9568)
				)
			)
		)
	)
	(footprint ""
		(layer "F.Cu")
		(at 342.2142 -94.107 90)
		(property "Reference" "CT72"
			(at -0.8382 -0.67818 90)
			(unlocked yes)
			(layer "F.SilkS")
			(effects
				(font
					(size 0.4064 0.254)
					(thickness 0.1524)
				)
				(justify left)
			)
		)
		(property "Value" ""
			(at 0 0 90)
			(layer "F.Fab")
			(effects
				(font
					(size 1.27 1.27)
				)
			)
		)
		(duplicate_pad_numbers_are_jumpers no)
		(fp_poly
			(pts
				(xy 0.3048 -0.1016) (xy 0.3048 0.9906) (xy -0.3048 0.9906) (xy -0.3048 -0.1016)
			)
			(stroke
				(width 0)
				(type default)
			)
			(fill no)
			(layer "F.CrtYd")
		)
		(fp_line
			(start 0.3048 -0.1016)
			(end -0.3048 -0.1016)
			(stroke
				(width 0.1)
				(type default)
			)
			(layer "F.Fab")
		)
		(fp_line
			(start -0.3048 -0.1016)
			(end -0.3048 0.9906)
			(stroke
				(width 0.1)
				(type default)
			)
			(layer "F.Fab")
		)
		(fp_line
			(start 0.3048 0.9906)
			(end 0.3048 -0.1016)
			(stroke
				(width 0.1)
				(type default)
			)
			(layer "F.Fab")
		)
		(fp_line
			(start -0.3048 0.9906)
			(end 0.3048 0.9906)
			(stroke
				(width 0.1)
				(type default)
			)
			(layer "F.Fab")
		)
		(pad "1" smd rect
			(at 0 0 90)
			(size 0.508 0.508)
			(layers "F.Cu" "F.Mask" "F.Paste")
			(net "VR_PVCCIO_CPU0_PH1_SW")
		)
		(pad "2" smd rect
			(at 0 0.889 90)
			(size 0.508 0.508)
			(layers "F.Cu" "F.Mask" "F.Paste")
			(net "VR_PVCCIO_CPU0_PH1_SW_RC")
		)
		(zone
			(layer "F.Cu")
			(hatch none 0.5)
			(connect_pads
				(clearance 0)
			)
			(min_thickness 0.25)
			(keepout
				(tracks allowed)
				(vias not_allowed)
				(pads allowed)
				(copperpour not_allowed)
				(footprints allowed)
			)
			(placement
				(enabled no)
				(sheetname "")
			)
			(fill
				(thermal_gap 0.5)
				(thermal_bridge_width 0.5)
				(island_removal_mode 0)
			)
			(polygon
				(pts
					(xy 342.4682 -93.853) (xy 342.4682 -94.361) (xy 342.8492 -94.361) (xy 342.8492 -93.853)
				)
			)
		)
		(zone
			(layer "F.Cu")
			(hatch none 0.5)
			(connect_pads
				(clearance 0)
			)
			(min_thickness 0.25)
			(keepout
				(tracks not_allowed)
				(vias allowed)
				(pads allowed)
				(copperpour not_allowed)
				(footprints allowed)
			)
			(placement
				(enabled no)
				(sheetname "")
			)
			(fill
				(thermal_gap 0.5)
				(thermal_bridge_width 0.5)
				(island_removal_mode 0)
			)
			(polygon
				(pts
					(xy 342.8492 -93.853) (xy 342.8492 -94.361) (xy 342.4682 -94.361) (xy 342.4682 -93.853)
				)
			)
		)
	)
)
